(kicad_pcb
	(version 20260206)
	(generator "pcbnew")
	(generator_version "10.0")
	(general
		(thickness 1.6)
		(legacy_teardrops no)
	)
	(paper "A4")
	(title_block
		(title "04192023_DAF0TMB3IC0_F0TG_MB_C_brd_V02_OCP.brd")
		(comment 1 "Grand Teton / footprints 2334-2334 of 8354")
	)
	(layers
		(0 "F.Cu" signal "TOP")
		(4 "In1.Cu" signal "GND")
		(6 "In2.Cu" signal "IN1")
		(8 "In3.Cu" signal "GND1")
		(10 "In4.Cu" signal "IN2")
		(12 "In5.Cu" signal "GND2")
		(14 "In6.Cu" signal "IN3")
		(16 "In7.Cu" signal "GND3")
		(18 "In8.Cu" signal "VCC")
		(20 "In9.Cu" signal "VCC1")
		(22 "In10.Cu" signal "GND4")
		(24 "In11.Cu" signal "IN4")
		(26 "In12.Cu" signal "GND5")
		(28 "In13.Cu" signal "IN5")
		(30 "In14.Cu" signal "GND6")
		(32 "In15.Cu" signal "IN6")
		(34 "In16.Cu" signal "GND7")
		(2 "B.Cu" signal "BOTTOM")
		(9 "F.Adhes" user "F.Adhesive")
		(11 "B.Adhes" user "B.Adhesive")
		(13 "F.Paste" user "Package Geometry/Pastemask Top")
		(15 "B.Paste" user "Package Geometry/Pastemask Bottom")
		(5 "F.SilkS" user "Ref Des/Silkscreen Top")
		(7 "B.SilkS" user "Ref Des/Silkscreen Bottom")
		(1 "F.Mask" user "Board Geometry/Soldermask Top")
		(3 "B.Mask" user "Board Geometry/Soldermask Bottom")
		(17 "Dwgs.User" user "User.Drawings")
		(19 "Cmts.User" user "User.Comments")
		(21 "Eco1.User" user "User.Eco1")
		(23 "Eco2.User" user "User.Eco2")
		(25 "Edge.Cuts" user "Board Geometry/Outline")
		(27 "Margin" user)
		(31 "F.CrtYd" user "Package Geometry/Place Bound Top")
		(29 "B.CrtYd" user "Package Geometry/Place Bound Bottom")
		(35 "F.Fab" user "Ref Des/Assembly Top")
		(33 "B.Fab" user "Ref Des/Assembly Bottom")
	)
	(footprint ""
		(layer "F.Cu")
		(at 151.627586 -408.517344 -90)
		(property "Reference" "C6718"
			(at 0 0 270)
			(layer "F.SilkS")
			(hide yes)
			(effects
				(font
					(size 1.27 1.27)
				)
			)
		)
		(property "Value" ""
			(at 0 0 270)
			(layer "F.Fab")
			(effects
				(font
					(size 1.27 1.27)
				)
			)
		)
		(duplicate_pad_numbers_are_jumpers no)
		(fp_line
			(start -0.299974 0.150114)
			(end -0.299974 -0.150114)
			(stroke
				(width 0.1)
				(type default)
			)
			(layer "F.Fab")
		)
		(fp_line
			(start 0.299974 0.150114)
			(end -0.299974 0.150114)
			(stroke
				(width 0.1)
				(type default)
			)
			(layer "F.Fab")
		)
		(fp_line
			(start -0.299974 -0.150114)
			(end 0.299974 -0.150114)
			(stroke
				(width 0.1)
				(type default)
			)
			(layer "F.Fab")
		)
		(fp_line
			(start 0.299974 -0.150114)
			(end 0.299974 0.150114)
			(stroke
				(width 0.1)
				(type default)
			)
			(layer "F.Fab")
		)
		(pad "1" smd rect
			(at -0.2667 0 270)
			(size 0.3048 0.381)
			(layers "F.Cu" "F.Mask" "F.Paste")
			(net "P5E_CPU1_P2_TX_BUF_C_DN<12>")
		)
		(pad "2" smd rect
			(at 0.2667 0 270)
			(size 0.3048 0.381)
			(layers "F.Cu" "F.Mask" "F.Paste")
			(net "P5E_CPU1_P2_TX_BUF_DN<12>")
		)
	)
)
